(kicad_pcb
	(version 20241229)
	(generator "pcbnew")
	(generator_version "9.0")
	(general
		(thickness 1.62)
		(legacy_teardrops no)
	)
	(paper "A4")
	(title_block
		(title "OCuLink to 10GbE adapter")
		(date "2026-02-23")
		(rev "1.1.0")
		(company "Antmicro Ltd")
		(comment 1 "www.antmicro.com")
		(comment 9 "footprints 189-193 of 510")
	)
	(layers
		(0 "F.Cu" signal)
		(4 "In1.Cu" signal)
		(6 "In2.Cu" signal)
		(8 "In3.Cu" signal)
		(10 "In4.Cu" signal)
		(12 "In5.Cu" signal)
		(14 "In6.Cu" signal)
		(2 "B.Cu" signal)
		(9 "F.Adhes" user "F.Adhesive")
		(11 "B.Adhes" user "B.Adhesive")
		(13 "F.Paste" user)
		(15 "B.Paste" user)
		(5 "F.SilkS" user "F.Silkscreen")
		(7 "B.SilkS" user "B.Silkscreen")
		(1 "F.Mask" user)
		(3 "B.Mask" user)
		(17 "Dwgs.User" user "User.Drawings")
		(19 "Cmts.User" user "User.Comments")
		(21 "Eco1.User" user "User.Eco1")
		(23 "Eco2.User" user "User.Eco2")
		(25 "Edge.Cuts" user)
		(27 "Margin" user)
		(31 "F.CrtYd" user "F.Courtyard")
		(29 "B.CrtYd" user "B.Courtyard")
		(35 "F.Fab" user)
		(33 "B.Fab" user)
	)
	(footprint "antmicro-footprints:C_0402_1005Metric"
		(layer "F.Cu")
		(at 69.1 96.55 180)
		(descr "Capacitor SMD 0402")
		(tags "capacitor SMD 0402")
		(property "Reference" "C128"
			(at 0.69 0.29 0)
			(layer "F.SilkS")
			(effects
				(font
					(size 0.7 0.7)
					(thickness 0.15)
				)
				(justify right top)
			)
		)
		(property "Value" "C_100n_0402"
			(at -1.022927 2.155213 0)
			(layer "F.Fab")
			(hide yes)
			(effects
				(font
					(size 0.7 0.7)
					(thickness 0.15)
				)
				(justify right top)
			)
		)
		(property "Datasheet" "https://www.murata.com/products/productdetail?partno=GRM155R61H104KE14%23"
			(at 0 0 0)
			(layer "F.Fab")
			(hide yes)
			(effects
				(font
					(size 1.27 1.27)
					(thickness 0.15)
				)
			)
		)
		(property "Description" "SMD Multilayer Ceramic Capacitor, 0.1 µF, 50 V, 0402 [1005 Metric], ± 10%, X5R, GRM Series"
			(at 0 0 0)
			(layer "F.Fab")
			(hide yes)
			(effects
				(font
					(size 1.27 1.27)
					(thickness 0.15)
				)
			)
		)
		(property "MPN" "GRM155R61H104KE14D"
			(at 0 0 180)
			(unlocked yes)
			(layer "F.Fab")
			(hide yes)
			(effects
				(font
					(size 1 1)
					(thickness 0.15)
				)
			)
		)
		(property "Val" "100n"
			(at 0 0 180)
			(unlocked yes)
			(layer "F.Fab")
			(hide yes)
			(effects
				(font
					(size 1 1)
					(thickness 0.15)
				)
			)
		)
		(property "Voltage" "50V"
			(at 0 0 180)
			(unlocked yes)
			(layer "F.Fab")
			(hide yes)
			(effects
				(font
					(size 1 1)
					(thickness 0.15)
				)
			)
		)
		(property "Dielectric" "X5R"
			(at 0 0 180)
			(unlocked yes)
			(layer "F.Fab")
			(hide yes)
			(effects
				(font
					(size 1 1)
					(thickness 0.15)
				)
			)
		)
		(property "Manufacturer" "Murata"
			(at 0 0 180)
			(unlocked yes)
			(layer "F.Fab")
			(hide yes)
			(effects
				(font
					(size 1 1)
					(thickness 0.15)
				)
			)
		)
		(property "License" "Apache-2.0"
			(at 0 0 180)
			(unlocked yes)
			(layer "F.Fab")
			(hide yes)
			(effects
				(font
					(size 1 1)
					(thickness 0.15)
				)
			)
		)
		(property "Author" "Antmicro"
			(at 0 0 180)
			(unlocked yes)
			(layer "F.Fab")
			(hide yes)
			(effects
				(font
					(size 1 1)
					(thickness 0.15)
				)
			)
		)
		(sheetname "/X710-AT2 power/")
		(sheetfile "x710-at2-power.kicad_sch")
		(attr smd)
		(fp_rect
			(start -0.925 -0.47)
			(end 0.925 0.47)
			(stroke
				(width 0.05)
				(type default)
			)
			(fill no)
			(layer "F.CrtYd")
		)
		(fp_line
			(start 0.504 0.248)
			(end -0.494 0.248)
			(stroke
				(width 0.15)
				(type solid)
			)
			(layer "F.Fab")
		)
		(fp_line
			(start 0.504 -0.25)
			(end 0.504 0.248)
			(stroke
				(width 0.15)
				(type solid)
			)
			(layer "F.Fab")
		)
		(fp_line
			(start -0.494 0.248)
			(end -0.494 -0.25)
			(stroke
				(width 0.15)
				(type solid)
			)
			(layer "F.Fab")
		)
		(fp_line
			(start -0.494 -0.25)
			(end 0.504 -0.25)
			(stroke
				(width 0.15)
				(type solid)
			)
			(layer "F.Fab")
		)
		(pad "1" smd roundrect
			(at -0.48 0 180)
			(size 0.59 0.64)
			(layers "F.Cu" "F.Mask" "F.Paste")
			(roundrect_rratio 0.25)
			(net 28 "GND")
			(pintype "passive")
		)
		(pad "2" smd roundrect
			(at 0.48 0 180)
			(size 0.59 0.64)
			(layers "F.Cu" "F.Mask" "F.Paste")
			(roundrect_rratio 0.25)
			(net 18 "+1V88")
			(pintype "passive")
		)
	)
	(footprint "antmicro-footprints:R_0402_1005Metric"
		(layer "F.Cu")
		(at 55.7 80.7 90)
		(descr "Resistor SMD 0402")
		(tags "resistor SMD 0402")
		(property "Reference" "R52"
			(at -1.06 -0.37 90)
			(layer "F.SilkS")
			(effects
				(font
					(size 0.7 0.7)
					(thickness 0.15)
				)
				(justify left bottom)
			)
		)
		(property "Value" "R_8k2_0402"
			(at -1.011843 1.772046 90)
			(layer "F.Fab")
			(hide yes)
			(effects
				(font
					(size 0.7 0.7)
					(thickness 0.15)
				)
				(justify left bottom)
			)
		)
		(property "Datasheet" "https://www.bourns.com/docs/product-datasheets/cr.pdf"
			(at 0 0 90)
			(layer "F.Fab")
			(hide yes)
			(effects
				(font
					(size 1.27 1.27)
					(thickness 0.15)
				)
			)
		)
		(property "Description" "SMD Chip Resistor"
			(at 0 0 90)
			(layer "F.Fab")
			(hide yes)
			(effects
				(font
					(size 1.27 1.27)
					(thickness 0.15)
				)
			)
		)
		(property "MPN" "CR0402-FX-8201GLF"
			(at 0 0 90)
			(unlocked yes)
			(layer "F.Fab")
			(hide yes)
			(effects
				(font
					(size 1 1)
					(thickness 0.15)
				)
			)
		)
		(property "Manufacturer" "Bourns"
			(at 0 0 90)
			(unlocked yes)
			(layer "F.Fab")
			(hide yes)
			(effects
				(font
					(size 1 1)
					(thickness 0.15)
				)
			)
		)
		(property "License" "Apache-2.0"
			(at 0 0 90)
			(unlocked yes)
			(layer "F.Fab")
			(hide yes)
			(effects
				(font
					(size 1 1)
					(thickness 0.15)
				)
			)
		)
		(property "Author" "Antmicro"
			(at 0 0 90)
			(unlocked yes)
			(layer "F.Fab")
			(hide yes)
			(effects
				(font
					(size 1 1)
					(thickness 0.15)
				)
			)
		)
		(property "Val" "8k2"
			(at 0 0 90)
			(unlocked yes)
			(layer "F.Fab")
			(hide yes)
			(effects
				(font
					(size 1 1)
					(thickness 0.15)
				)
			)
		)
		(property "Tolerance" "1%"
			(at 0 0 90)
			(unlocked yes)
			(layer "F.Fab")
			(hide yes)
			(effects
				(font
					(size 1 1)
					(thickness 0.15)
				)
			)
		)
		(sheetname "/X710-AT2 PCIe/")
		(sheetfile "x710-at2-pcie.kicad_sch")
		(attr smd)
		(fp_rect
			(start -0.925 -0.47)
			(end 0.925 0.47)
			(stroke
				(width 0.05)
				(type default)
			)
			(fill no)
			(layer "F.CrtYd")
		)
		(fp_rect
			(start -0.5 -0.25)
			(end 0.5 0.25)
			(stroke
				(width 0.15)
				(type solid)
			)
			(fill no)
			(layer "F.Fab")
		)
		(pad "1" smd roundrect
			(at -0.48 0 90)
			(size 0.59 0.64)
			(layers "F.Cu" "F.Mask" "F.Paste")
			(roundrect_rratio 0.25)
			(net 11 "/X710-AT2 PCIe/PCIe_JTAG.JTDI")
			(pintype "passive")
		)
		(pad "2" smd roundrect
			(at 0.48 0 90)
			(size 0.59 0.64)
			(layers "F.Cu" "F.Mask" "F.Paste")
			(roundrect_rratio 0.25)
			(net 7 "+3V3")
			(pintype "passive")
		)
	)
	(footprint "antmicro-footprints:R_0402_1005Metric"
		(layer "F.Cu")
		(at 56.1 100.55 90)
		(descr "Resistor SMD 0402")
		(tags "resistor SMD 0402")
		(property "Reference" "R15"
			(at -1.64 -2.47 180)
			(layer "F.SilkS")
			(effects
				(font
					(size 0.7 0.7)
					(thickness 0.14)
					(bold yes)
				)
				(justify left bottom)
			)
		)
		(property "Value" "R_63k4_0402"
			(at -1.011843 1.772046 90)
			(layer "F.Fab")
			(hide yes)
			(effects
				(font
					(size 0.7 0.7)
					(thickness 0.15)
				)
				(justify left bottom)
			)
		)
		(property "Datasheet" "https://industrial.panasonic.com/cdbs/www-data/pdf/RDM0000/AOA0000C307.pdf"
			(at 0 0 90)
			(layer "F.Fab")
			(hide yes)
			(effects
				(font
					(size 1.27 1.27)
					(thickness 0.15)
				)
			)
		)
		(property "Description" "SMD Chip Resistor, 63.4 kohm, ± 0.1%, 63 mW, 0402 [1005 Metric], Thin Film,  Precision"
			(at 0 0 90)
			(layer "F.Fab")
			(hide yes)
			(effects
				(font
					(size 1.27 1.27)
					(thickness 0.15)
				)
			)
		)
		(property "MPN" "ERA-2AEB6342X"
			(at 0 0 90)
			(unlocked yes)
			(layer "F.Fab")
			(hide yes)
			(effects
				(font
					(size 1 1)
					(thickness 0.15)
				)
			)
		)
		(property "Manufacturer" "Panasonic"
			(at 0 0 90)
			(unlocked yes)
			(layer "F.Fab")
			(hide yes)
			(effects
				(font
					(size 1 1)
					(thickness 0.15)
				)
			)
		)
		(property "License" "Apache-2.0"
			(at 0 0 90)
			(unlocked yes)
			(layer "F.Fab")
			(hide yes)
			(effects
				(font
					(size 1 1)
					(thickness 0.15)
				)
			)
		)
		(property "Author" "Antmicro"
			(at 0 0 90)
			(unlocked yes)
			(layer "F.Fab")
			(hide yes)
			(effects
				(font
					(size 1 1)
					(thickness 0.15)
				)
			)
		)
		(property "Val" "63k4"
			(at 0 0 90)
			(unlocked yes)
			(layer "F.Fab")
			(hide yes)
			(effects
				(font
					(size 1 1)
					(thickness 0.15)
				)
			)
		)
		(property "Tolerance" "0.1%"
			(at 0 0 90)
			(unlocked yes)
			(layer "F.Fab")
			(hide yes)
			(effects
				(font
					(size 1 1)
					(thickness 0.15)
				)
			)
		)
		(sheetname "/Power/")
		(sheetfile "power.kicad_sch")
		(attr smd)
		(fp_rect
			(start -0.925 -0.47)
			(end 0.925 0.47)
			(stroke
				(width 0.05)
				(type default)
			)
			(fill no)
			(layer "F.CrtYd")
		)
		(fp_rect
			(start -0.5 -0.25)
			(end 0.5 0.25)
			(stroke
				(width 0.15)
				(type solid)
			)
			(fill no)
			(layer "F.Fab")
		)
		(pad "1" smd roundrect
			(at -0.48 0 90)
			(size 0.59 0.64)
			(layers "F.Cu" "F.Mask" "F.Paste")
			(roundrect_rratio 0.25)
			(net 330 "/Power/1V88_FB")
			(pintype "passive")
		)
		(pad "2" smd roundrect
			(at 0.48 0 90)
			(size 0.59 0.64)
			(layers "F.Cu" "F.Mask" "F.Paste")
			(roundrect_rratio 0.25)
			(net 310 "/Power/+1V88_OUT")
			(pintype "passive")
		)
	)
	(footprint "antmicro-footprints:TP_SMD_0.75mm"
		(layer "F.Cu")
		(at 52.050001 121.500001)
		(property "Reference" "TP18"
			(at -2.93 0.5 0)
			(layer "F.SilkS")
			(hide yes)
			(effects
				(font
					(size 0.7 0.7)
					(thickness 0.15)
				)
				(justify left bottom)
			)
		)
		(property "Value" "TP_0.75mm_SMD"
			(at 0 1.2 0)
			(layer "F.Fab")
			(hide yes)
			(effects
				(font
					(size 0.7 0.7)
					(thickness 0.15)
				)
				(justify left bottom)
			)
		)
		(property "Description" "SMT test point"
			(at 0 0 0)
			(layer "F.Fab")
			(hide yes)
			(effects
				(font
					(size 1.27 1.27)
					(thickness 0.15)
				)
			)
		)
		(property "MPN" ""
			(at 0 0 0)
			(unlocked yes)
			(layer "F.Fab")
			(hide yes)
			(effects
				(font
					(size 1 1)
					(thickness 0.15)
				)
			)
		)
		(property "Manufacturer" ""
			(at 0 0 0)
			(unlocked yes)
			(layer "F.Fab")
			(hide yes)
			(effects
				(font
					(size 1 1)
					(thickness 0.15)
				)
			)
		)
		(property "Author" "Antmicro"
			(at 0 0 0)
			(unlocked yes)
			(layer "F.Fab")
			(hide yes)
			(effects
				(font
					(size 1 1)
					(thickness 0.15)
				)
			)
		)
		(property "License" "Apache-2.0"
			(at 0 0 0)
			(unlocked yes)
			(layer "F.Fab")
			(hide yes)
			(effects
				(font
					(size 1 1)
					(thickness 0.15)
				)
			)
		)
		(sheetname "/Power/")
		(sheetfile "power.kicad_sch")
		(attr exclude_from_pos_files exclude_from_bom)
		(fp_circle
			(center 0 0)
			(end 0.475 0)
			(stroke
				(width 0.05)
				(type default)
			)
			(fill no)
			(layer "F.CrtYd")
		)
		(pad "1" smd circle
			(at 0 0)
			(size 0.75 0.75)
			(layers "F.Cu" "F.Mask")
			(net 312 "/Power/+1V0_OUT")
			(pinfunction "1")
			(pintype "passive")
		)
	)
	(footprint "antmicro-footprints:SOT-23-3"
		(layer "F.Cu")
		(at 55.65 72.615 90)
		(property "Reference" "Q1"
			(at -1.8 -1.8 90)
			(layer "F.SilkS")
			(effects
				(font
					(size 0.7 0.7)
					(thickness 0.15)
				)
				(justify left bottom)
			)
		)
		(property "Value" "2N7002_SOT-23-3"
			(at -1.9 2.7 90)
			(layer "F.Fab")
			(hide yes)
			(effects
				(font
					(size 0.7 0.7)
					(thickness 0.15)
				)
				(justify left bottom)
			)
		)
		(property "Datasheet" "https://www.onsemi.com/pub/Collateral/NDS7002A-D.PDF"
			(at 0 0 90)
			(layer "F.Fab")
			(hide yes)
			(effects
				(font
					(size 1.27 1.27)
					(thickness 0.15)
				)
			)
		)
		(property "Description" "Power MOSFET, N Channel, 60 V, 115 mA, 1.2 ohm, SOT-23, Surface Mount"
			(at 0 0 90)
			(layer "F.Fab")
			(hide yes)
			(effects
				(font
					(size 1.27 1.27)
					(thickness 0.15)
				)
			)
		)
		(property "MPN" "2N7002"
			(at 0 0 90)
			(unlocked yes)
			(layer "F.Fab")
			(hide yes)
			(effects
				(font
					(size 1 1)
					(thickness 0.15)
				)
			)
		)
		(property "Manufacturer" "ON Semiconductor"
			(at 0 0 90)
			(unlocked yes)
			(layer "F.Fab")
			(hide yes)
			(effects
				(font
					(size 1 1)
					(thickness 0.15)
				)
			)
		)
		(property "Author" "Antmicro"
			(at 0 0 90)
			(unlocked yes)
			(layer "F.Fab")
			(hide yes)
			(effects
				(font
					(size 1 1)
					(thickness 0.15)
				)
			)
		)
		(property "License" "Apache-2.0"
			(at 0 0 90)
			(unlocked yes)
			(layer "F.Fab")
			(hide yes)
			(effects
				(font
					(size 1 1)
					(thickness 0.15)
				)
			)
		)
		(sheetname "/Power/")
		(sheetfile "power.kicad_sch")
		(attr smd)
		(fp_line
			(start 0.7 -1.5)
			(end -0.7 -1.5)
			(stroke
				(width 0.15)
				(type solid)
			)
			(layer "F.SilkS")
		)
		(fp_line
			(start -0.85 -1.35)
			(end -0.7 -1.5)
			(stroke
				(width 0.15)
				(type solid)
			)
			(layer "F.SilkS")
		)
		(fp_line
			(start -1.45 -1.35)
			(end -0.85 -1.35)
			(stroke
				(width 0.15)
				(type solid)
			)
			(layer "F.SilkS")
		)
		(fp_line
			(start 0.7 -0.4)
			(end 0.7 -1.5)
			(stroke
				(width 0.15)
				(type solid)
			)
			(layer "F.SilkS")
		)
		(fp_line
			(start 0.7 0.4)
			(end 0.7 1.5)
			(stroke
				(width 0.15)
				(type solid)
			)
			(layer "F.SilkS")
		)
		(fp_line
			(start 0.7 1.5)
			(end -0.7 1.5)
			(stroke
				(width 0.15)
				(type solid)
			)
			(layer "F.SilkS")
		)
		(fp_line
			(start -0.7 1.5)
			(end -0.7 1.35)
			(stroke
				(width 0.15)
				(type solid)
			)
			(layer "F.SilkS")
		)
		(fp_line
			(start 0.825 -1.6)
			(end 0.825 -0.45)
			(stroke
				(width 0.05)
				(type solid)
			)
			(layer "F.CrtYd")
		)
		(fp_line
			(start -0.9 -1.6)
			(end 0.825 -1.6)
			(stroke
				(width 0.05)
				(type solid)
			)
			(layer "F.CrtYd")
		)
		(fp_line
			(start -0.9 -1.6)
			(end -0.9 -1.4)
			(stroke
				(width 0.05)
				(type solid)
			)
			(layer "F.CrtYd")
		)
		(fp_line
			(start -0.9 -1.4)
			(end -1.75 -1.4)
			(stroke
				(width 0.05)
				(type solid)
			)
			(layer "F.CrtYd")
		)
		(fp_line
			(start -0.85 -0.5)
			(end -1.75 -0.5)
			(stroke
				(width 0.05)
				(type solid)
			)
			(layer "F.CrtYd")
		)
		(fp_line
			(start -1.75 -0.5)
			(end -1.75 -1.4)
			(stroke
				(width 0.05)
				(type solid)
			)
			(layer "F.CrtYd")
		)
		(fp_line
			(start 1.75 -0.45)
			(end 1.75 0.45)
			(stroke
				(width 0.05)
				(type solid)
			)
			(layer "F.CrtYd")
		)
		(fp_line
			(start 0.825 -0.45)
			(end 1.75 -0.45)
			(stroke
				(width 0.05)
				(type solid)
			)
			(layer "F.CrtYd")
		)
		(fp_line
			(start 1.75 0.45)
			(end 0.85 0.45)
			(stroke
				(width 0.05)
				(type solid)
			)
			(layer "F.CrtYd")
		)
		(fp_line
			(start 0.85 0.45)
			(end 0.85 1.65)
			(stroke
				(width 0.05)
				(type solid)
			)
			(layer "F.CrtYd")
		)
		(fp_line
			(start -0.85 0.5)
			(end -0.85 -0.5)
			(stroke
				(width 0.05)
				(type solid)
			)
			(layer "F.CrtYd")
		)
		(fp_line
			(start -1.75 0.5)
			(end -0.85 0.5)
			(stroke
				(width 0.05)
				(type solid)
			)
			(layer "F.CrtYd")
		)
		(fp_line
			(start -0.85 1.4)
			(end -1.75 1.4)
			(stroke
				(width 0.05)
				(type solid)
			)
			(layer "F.CrtYd")
		)
		(fp_line
			(start -1.75 1.4)
			(end -1.75 0.5)
			(stroke
				(width 0.05)
				(type solid)
			)
			(layer "F.CrtYd")
		)
		(fp_line
			(start 0.85 1.65)
			(end -0.85 1.65)
			(stroke
				(width 0.05)
				(type solid)
			)
			(layer "F.CrtYd")
		)
		(fp_line
			(start -0.85 1.65)
			(end -0.85 1.4)
			(stroke
				(width 0.05)
				(type solid)
			)
			(layer "F.CrtYd")
		)
		(fp_line
			(start -0.437 -1.526)
			(end 0.688 -1.526)
			(stroke
				(width 0.15)
				(type solid)
			)
			(layer "F.Fab")
		)
		(fp_line
			(start -0.437 -1.526)
			(end -0.712 -1.325)
			(stroke
				(width 0.15)
				(type solid)
			)
			(layer "F.Fab")
		)
		(fp_line
			(start -0.712 -1.325)
			(end -0.712 1.523)
			(stroke
				(width 0.15)
				(type solid)
			)
			(layer "F.Fab")
		)
		(fp_line
			(start 0.688 1.519)
			(end 0.688 -1.52)
			(stroke
				(width 0.15)
				(type solid)
			)
			(layer "F.Fab")
		)
		(fp_line
			(start -0.712 1.519)
			(end 0.688 1.519)
			(stroke
				(width 0.15)
				(type solid)
			)
			(layer "F.Fab")
		)
		(pad "1" smd roundrect
			(at -1.1 -0.951 90)
			(size 1 0.6)
			(layers "F.Cu" "F.Mask" "F.Paste")
			(roundrect_rratio 0.15)
			(net 392 "/Power/ALL_RAILS_OK")
			(pinfunction "G")
			(pintype "input")
		)
		(pad "2" smd roundrect
			(at -1.1 0.949 90)
			(size 1 0.6)
			(layers "F.Cu" "F.Mask" "F.Paste")
			(roundrect_rratio 0.15)
			(net 28 "GND")
			(pinfunction "S")
			(pintype "passive")
		)
		(pad "3" smd roundrect
			(at 1.1 -0.0005 90)
			(size 1 0.6)
			(layers "F.Cu" "F.Mask" "F.Paste")
			(roundrect_rratio 0.15)
			(net 393 "/OCuLink/~{CPRSNT}")
			(pinfunction "D")
			(pintype "passive")
		)
	)
)
